# S9S_MB_2U (Grand Teton) — schematic netlist excerpt (pin names and nets, part order shuffled) for the footprints in the layout excerpt that follows; sources: Cadence DE-HDL packaged netlist, KiCad conversion of 03242023_DA0F0TMBIJ0_F0T_Motherboard_J_brd_V01_OCP.brd

R1919  Q_RES  33.2 1% CHIP  pkg 0402LF  page 222 : A = PWRGD_P3V3_AUX ; B = PWRGD_P3V3_AUX_PLD
R2728  Q_RES  33.2 1% CHIP  pkg 0402LF  page 114 : A = PWRGD_CHB_CPU0_DIMM1 ; B = PWRGD_FAIL_CPU0_AB

(kicad_pcb
	(version 20260206)
	(generator "pcbnew")
	(generator_version "10.0")
	(general
		(thickness 1.6)
		(legacy_teardrops no)
	)
	(paper "A4")
	(title_block
		(title "03242023_DA0F0TMBIJ0_F0T_Motherboard_J_brd_V01_OCP.brd")
		(comment 1 "Grand Teton / footprints 4878-4879 of 6105")
	)
	(layers
		(0 "F.Cu" signal "TOP")
		(4 "In1.Cu" signal "GND")
		(6 "In2.Cu" signal "IN1")
		(8 "In3.Cu" signal "GND1")
		(10 "In4.Cu" signal "IN2")
		(12 "In5.Cu" signal "GND2")
		(14 "In6.Cu" signal "IN3")
		(16 "In7.Cu" signal "GND3")
		(18 "In8.Cu" signal "VCC")
		(20 "In9.Cu" signal "VCC1")
		(22 "In10.Cu" signal "GND4")
		(24 "In11.Cu" signal "IN4")
		(26 "In12.Cu" signal "GND5")
		(28 "In13.Cu" signal "IN5")
		(30 "In14.Cu" signal "GND6")
		(32 "In15.Cu" signal "IN6")
		(34 "In16.Cu" signal "GND7")
		(2 "B.Cu" signal "BOTTOM")
		(9 "F.Adhes" user "F.Adhesive")
		(11 "B.Adhes" user "B.Adhesive")
		(13 "F.Paste" user "Package Geometry/Pastemask Top")
		(15 "B.Paste" user "Package Geometry/Pastemask Bottom")
		(5 "F.SilkS" user "Ref Des/Silkscreen Top")
		(7 "B.SilkS" user "Ref Des/Silkscreen Bottom")
		(1 "F.Mask" user "Board Geometry/Soldermask Top")
		(3 "B.Mask" user "Board Geometry/Soldermask Bottom")
		(17 "Dwgs.User" user "User.Drawings")
		(19 "Cmts.User" user "User.Comments")
		(21 "Eco1.User" user "User.Eco1")
		(23 "Eco2.User" user "User.Eco2")
		(25 "Edge.Cuts" user "Board Geometry/Outline")
		(27 "Margin" user)
		(31 "F.CrtYd" user "Package Geometry/Place Bound Top")
		(29 "B.CrtYd" user "Package Geometry/Place Bound Bottom")
		(35 "F.Fab" user "Ref Des/Assembly Top")
		(33 "B.Fab" user "Ref Des/Assembly Bottom")
	)
	(footprint ""
		(layer "B.Cu")
		(at 290.301934 -319.068958 -90)
		(property "Reference" "R2728"
			(at 0 0 90)
			(layer "B.SilkS")
			(hide yes)
			(effects
				(font
					(size 1.27 1.27)
				)
				(justify mirror)
			)
		)
		(property "Value" ""
			(at 0 0 90)
			(layer "B.Fab")
			(effects
				(font
					(size 1.27 1.27)
				)
				(justify mirror)
			)
		)
		(duplicate_pad_numbers_are_jumpers no)
		(fp_line
			(start -0.7874 0.4064)
			(end 0.7874 0.4064)
			(stroke
				(width 0.1524)
				(type default)
			)
			(layer "B.SilkS")
		)
		(fp_line
			(start 0.7874 0.4064)
			(end 0.7874 -0.4064)
			(stroke
				(width 0.1524)
				(type default)
			)
			(layer "B.SilkS")
		)
		(fp_line
			(start -0.7874 -0.4064)
			(end -0.7874 0.4064)
			(stroke
				(width 0.1524)
				(type default)
			)
			(layer "B.SilkS")
		)
		(fp_line
			(start 0.7874 -0.4064)
			(end -0.7874 -0.4064)
			(stroke
				(width 0.1524)
				(type default)
			)
			(layer "B.SilkS")
		)
		(fp_line
			(start -0.67945 0.3048)
			(end -0.120396 0.3048)
			(stroke
				(width 0.1)
				(type default)
			)
			(layer "B.Fab")
		)
		(fp_line
			(start -0.120396 0.3048)
			(end -0.120396 0.2794)
			(stroke
				(width 0.1)
				(type default)
			)
			(layer "B.Fab")
		)
		(fp_line
			(start 0.12065 0.3048)
			(end 0.67945 0.3048)
			(stroke
				(width 0.1)
				(type default)
			)
			(layer "B.Fab")
		)
		(fp_line
			(start 0.67945 0.3048)
			(end 0.67945 -0.305054)
			(stroke
				(width 0.1)
				(type default)
			)
			(layer "B.Fab")
		)
		(fp_line
			(start -0.120396 0.2794)
			(end 0.12065 0.2794)
			(stroke
				(width 0.1)
				(type default)
			)
			(layer "B.Fab")
		)
		(fp_line
			(start 0.12065 0.2794)
			(end 0.12065 0.3048)
			(stroke
				(width 0.1)
				(type default)
			)
			(layer "B.Fab")
		)
		(fp_line
			(start -0.12065 -0.2794)
			(end -0.12065 -0.3048)
			(stroke
				(width 0.1)
				(type default)
			)
			(layer "B.Fab")
		)
		(fp_line
			(start 0.12065 -0.2794)
			(end -0.12065 -0.2794)
			(stroke
				(width 0.1)
				(type default)
			)
			(layer "B.Fab")
		)
		(fp_line
			(start -0.67945 -0.3048)
			(end -0.67945 0.3048)
			(stroke
				(width 0.1)
				(type default)
			)
			(layer "B.Fab")
		)
		(fp_line
			(start -0.12065 -0.3048)
			(end -0.67945 -0.3048)
			(stroke
				(width 0.1)
				(type default)
			)
			(layer "B.Fab")
		)
		(fp_line
			(start 0.12065 -0.305054)
			(end 0.12065 -0.2794)
			(stroke
				(width 0.1)
				(type default)
			)
			(layer "B.Fab")
		)
		(fp_line
			(start 0.67945 -0.305054)
			(end 0.12065 -0.305054)
			(stroke
				(width 0.1)
				(type default)
			)
			(layer "B.Fab")
		)
		(pad "1" smd circle
			(at 0.40005 0 90)
			(size 0 0)
			(layers "B.Cu" "B.Mask" "B.Paste")
			(net "PWRGD_CHB_CPU0_DIMM1")
		)
		(pad "2" smd circle
			(at -0.40005 0 90)
			(size 0 0)
			(layers "B.Cu" "B.Mask" "B.Paste")
			(net "PWRGD_FAIL_CPU0_AB")
		)
	)
	(footprint ""
		(layer "B.Cu")
		(at 164.64788 -116.296948 180)
		(property "Reference" "R1919"
			(at 0 0 0)
			(layer "B.SilkS")
			(hide yes)
			(effects
				(font
					(size 1.27 1.27)
				)
				(justify mirror)
			)
		)
		(property "Value" ""
			(at 0 0 0)
			(layer "B.Fab")
			(effects
				(font
					(size 1.27 1.27)
				)
				(justify mirror)
			)
		)
		(duplicate_pad_numbers_are_jumpers no)
		(fp_line
			(start 0.7874 0.4064)
			(end 0.7874 -0.4064)
			(stroke
				(width 0.1524)
				(type default)
			)
			(layer "B.SilkS")
		)
		(fp_line
			(start 0.7874 -0.4064)
			(end -0.7874 -0.4064)
			(stroke
				(width 0.1524)
				(type default)
			)
			(layer "B.SilkS")
		)
		(fp_line
			(start -0.7874 0.4064)
			(end 0.7874 0.4064)
			(stroke
				(width 0.1524)
				(type default)
			)
			(layer "B.SilkS")
		)
		(fp_line
			(start -0.7874 -0.4064)
			(end -0.7874 0.4064)
			(stroke
				(width 0.1524)
				(type default)
			)
			(layer "B.SilkS")
		)
		(fp_line
			(start 0.67945 0.3048)
			(end 0.67945 -0.305054)
			(stroke
				(width 0.1)
				(type default)
			)
			(layer "B.Fab")
		)
		(fp_line
			(start 0.67945 -0.305054)
			(end 0.12065 -0.305054)
			(stroke
				(width 0.1)
				(type default)
			)
			(layer "B.Fab")
		)
		(fp_line
			(start 0.12065 0.3048)
			(end 0.67945 0.3048)
			(stroke
				(width 0.1)
				(type default)
			)
			(layer "B.Fab")
		)
		(fp_line
			(start 0.12065 0.2794)
			(end 0.12065 0.3048)
			(stroke
				(width 0.1)
				(type default)
			)
			(layer "B.Fab")
		)
		(fp_line
			(start 0.12065 -0.2794)
			(end -0.12065 -0.2794)
			(stroke
				(width 0.1)
				(type default)
			)
			(layer "B.Fab")
		)
		(fp_line
			(start 0.12065 -0.305054)
			(end 0.12065 -0.2794)
			(stroke
				(width 0.1)
				(type default)
			)
			(layer "B.Fab")
		)
		(fp_line
			(start -0.120396 0.3048)
			(end -0.120396 0.2794)
			(stroke
				(width 0.1)
				(type default)
			)
			(layer "B.Fab")
		)
		(fp_line
			(start -0.120396 0.2794)
			(end 0.12065 0.2794)
			(stroke
				(width 0.1)
				(type default)
			)
			(layer "B.Fab")
		)
		(fp_line
			(start -0.12065 -0.2794)
			(end -0.12065 -0.3048)
			(stroke
				(width 0.1)
				(type default)
			)
			(layer "B.Fab")
		)
		(fp_line
			(start -0.12065 -0.3048)
			(end -0.67945 -0.3048)
			(stroke
				(width 0.1)
				(type default)
			)
			(layer "B.Fab")
		)
		(fp_line
			(start -0.67945 0.3048)
			(end -0.120396 0.3048)
			(stroke
				(width 0.1)
				(type default)
			)
			(layer "B.Fab")
		)
		(fp_line
			(start -0.67945 -0.3048)
			(end -0.67945 0.3048)
			(stroke
				(width 0.1)
				(type default)
			)
			(layer "B.Fab")
		)
		(pad "1" smd circle
			(at 0.40005 0)
			(size 0 0)
			(layers "B.Cu" "B.Mask" "B.Paste")
			(net "PWRGD_P3V3_AUX")
		)
		(pad "2" smd circle
			(at -0.40005 0)
			(size 0 0)
			(layers "B.Cu" "B.Mask" "B.Paste")
			(net "PWRGD_P3V3_AUX_PLD")
		)
	)
)
